(kicad_pcb
	(version 20260206)
	(generator "pcbnew")
	(generator_version "10.0")
	(general
		(thickness 1.6)
		(legacy_teardrops no)
	)
	(paper "A4")
	(title_block
		(title "9054_F0T_PDB_BD_GPU_F_V04_1213_1550_OCP.brd")
		(comment 1 "Grand Teton / footprints 440-446 of 608")
	)
	(layers
		(0 "F.Cu" signal "TOP")
		(4 "In1.Cu" signal "GND")
		(6 "In2.Cu" signal "IN1")
		(8 "In3.Cu" signal "GND1")
		(10 "In4.Cu" signal "VCC")
		(12 "In5.Cu" signal "VCC1")
		(14 "In6.Cu" signal "GND2")
		(16 "In7.Cu" signal "IN2")
		(18 "In8.Cu" signal "GND3")
		(2 "B.Cu" signal "BOTTOM")
		(9 "F.Adhes" user "F.Adhesive")
		(11 "B.Adhes" user "B.Adhesive")
		(13 "F.Paste" user "Package Geometry/Pastemask Top")
		(15 "B.Paste" user "Package Geometry/Pastemask Bottom")
		(5 "F.SilkS" user "Ref Des/Silkscreen Top")
		(7 "B.SilkS" user "Ref Des/Silkscreen Bottom")
		(1 "F.Mask" user "Board Geometry/Soldermask Top")
		(3 "B.Mask" user "Board Geometry/Soldermask Bottom")
		(17 "Dwgs.User" user "User.Drawings")
		(19 "Cmts.User" user "User.Comments")
		(21 "Eco1.User" user "User.Eco1")
		(23 "Eco2.User" user "User.Eco2")
		(25 "Edge.Cuts" user "Board Geometry/Outline")
		(27 "Margin" user)
		(31 "F.CrtYd" user "Package Geometry/Place Bound Top")
		(29 "B.CrtYd" user "Package Geometry/Place Bound Bottom")
		(35 "F.Fab" user "Ref Des/Assembly Top")
		(33 "B.Fab" user "Ref Des/Assembly Bottom")
	)
	(footprint ""
		(layer "B.Cu")
		(at 297.3324 -76.962)
		(property "Reference" "PR25"
			(at 0 0 0)
			(layer "B.SilkS")
			(hide yes)
			(effects
				(font
					(size 1.27 1.27)
				)
				(justify mirror)
			)
		)
		(property "Value" ""
			(at 0 0 0)
			(layer "B.Fab")
			(effects
				(font
					(size 1.27 1.27)
				)
				(justify mirror)
			)
		)
		(duplicate_pad_numbers_are_jumpers no)
		(fp_line
			(start -1.651 -0.8382)
			(end -1.651 0.8382)
			(stroke
				(width 0.1524)
				(type default)
			)
			(layer "B.SilkS")
		)
		(fp_line
			(start -1.651 0.8382)
			(end 1.651 0.8382)
			(stroke
				(width 0.1524)
				(type default)
			)
			(layer "B.SilkS")
		)
		(fp_line
			(start 1.651 -0.8382)
			(end -1.651 -0.8382)
			(stroke
				(width 0.1524)
				(type default)
			)
			(layer "B.SilkS")
		)
		(fp_line
			(start 1.651 0.8382)
			(end 1.651 -0.8382)
			(stroke
				(width 0.1524)
				(type default)
			)
			(layer "B.SilkS")
		)
		(fp_line
			(start -1.560576 -0.7366)
			(end -1.524 -0.7366)
			(stroke
				(width 0.1)
				(type default)
			)
			(layer "B.Fab")
		)
		(fp_line
			(start -1.560576 0.7366)
			(end -1.560576 -0.7366)
			(stroke
				(width 0.1)
				(type default)
			)
			(layer "B.Fab")
		)
		(fp_line
			(start -1.524 -0.7366)
			(end 1.524 -0.7366)
			(stroke
				(width 0.1)
				(type default)
			)
			(layer "B.Fab")
		)
		(fp_line
			(start -1.524 0.7366)
			(end -1.560576 0.7366)
			(stroke
				(width 0.1)
				(type default)
			)
			(layer "B.Fab")
		)
		(fp_line
			(start 1.524 -0.7366)
			(end 1.559814 -0.7366)
			(stroke
				(width 0.1)
				(type default)
			)
			(layer "B.Fab")
		)
		(fp_line
			(start 1.524 0.7366)
			(end -1.524 0.7366)
			(stroke
				(width 0.1)
				(type default)
			)
			(layer "B.Fab")
		)
		(fp_line
			(start 1.559814 -0.7366)
			(end 1.559814 0.7366)
			(stroke
				(width 0.1)
				(type default)
			)
			(layer "B.Fab")
		)
		(fp_line
			(start 1.559814 0.7366)
			(end 1.524 0.7366)
			(stroke
				(width 0.1)
				(type default)
			)
			(layer "B.Fab")
		)
		(pad "1" smd rect
			(at 0.94996 0)
			(size 1.1176 1.3716)
			(layers "B.Cu" "B.Mask" "B.Paste")
			(net "P52V_HS1")
		)
		(pad "2" smd rect
			(at -0.94996 0)
			(size 1.1176 1.3716)
			(layers "B.Cu" "B.Mask" "B.Paste")
			(net "P52V_HS1_VDSFB")
		)
	)
	(footprint ""
		(layer "B.Cu")
		(at 416.833558 -32.767016 -90)
		(property "Reference" "R5924"
			(at 0 0 90)
			(layer "B.SilkS")
			(hide yes)
			(effects
				(font
					(size 1.27 1.27)
				)
				(justify mirror)
			)
		)
		(property "Value" ""
			(at 0 0 90)
			(layer "B.Fab")
			(effects
				(font
					(size 1.27 1.27)
				)
				(justify mirror)
			)
		)
		(duplicate_pad_numbers_are_jumpers no)
		(fp_line
			(start -0.7874 0.4064)
			(end 0.7874 0.4064)
			(stroke
				(width 0.1524)
				(type default)
			)
			(layer "B.SilkS")
		)
		(fp_line
			(start 0.7874 0.4064)
			(end 0.7874 -0.4064)
			(stroke
				(width 0.1524)
				(type default)
			)
			(layer "B.SilkS")
		)
		(fp_line
			(start -0.7874 -0.4064)
			(end -0.7874 0.4064)
			(stroke
				(width 0.1524)
				(type default)
			)
			(layer "B.SilkS")
		)
		(fp_line
			(start 0.7874 -0.4064)
			(end -0.7874 -0.4064)
			(stroke
				(width 0.1524)
				(type default)
			)
			(layer "B.SilkS")
		)
		(fp_line
			(start -0.67945 0.3048)
			(end -0.120396 0.3048)
			(stroke
				(width 0.1)
				(type default)
			)
			(layer "B.Fab")
		)
		(fp_line
			(start -0.120396 0.3048)
			(end -0.120396 0.2794)
			(stroke
				(width 0.1)
				(type default)
			)
			(layer "B.Fab")
		)
		(fp_line
			(start 0.12065 0.3048)
			(end 0.67945 0.3048)
			(stroke
				(width 0.1)
				(type default)
			)
			(layer "B.Fab")
		)
		(fp_line
			(start 0.67945 0.3048)
			(end 0.67945 -0.305054)
			(stroke
				(width 0.1)
				(type default)
			)
			(layer "B.Fab")
		)
		(fp_line
			(start -0.120396 0.2794)
			(end 0.12065 0.2794)
			(stroke
				(width 0.1)
				(type default)
			)
			(layer "B.Fab")
		)
		(fp_line
			(start 0.12065 0.2794)
			(end 0.12065 0.3048)
			(stroke
				(width 0.1)
				(type default)
			)
			(layer "B.Fab")
		)
		(fp_line
			(start -0.12065 -0.2794)
			(end -0.12065 -0.3048)
			(stroke
				(width 0.1)
				(type default)
			)
			(layer "B.Fab")
		)
		(fp_line
			(start 0.12065 -0.2794)
			(end -0.12065 -0.2794)
			(stroke
				(width 0.1)
				(type default)
			)
			(layer "B.Fab")
		)
		(fp_line
			(start -0.67945 -0.3048)
			(end -0.67945 0.3048)
			(stroke
				(width 0.1)
				(type default)
			)
			(layer "B.Fab")
		)
		(fp_line
			(start -0.12065 -0.3048)
			(end -0.67945 -0.3048)
			(stroke
				(width 0.1)
				(type default)
			)
			(layer "B.Fab")
		)
		(fp_line
			(start 0.12065 -0.305054)
			(end 0.12065 -0.2794)
			(stroke
				(width 0.1)
				(type default)
			)
			(layer "B.Fab")
		)
		(fp_line
			(start 0.67945 -0.305054)
			(end 0.12065 -0.305054)
			(stroke
				(width 0.1)
				(type default)
			)
			(layer "B.Fab")
		)
		(pad "1" smd circle
			(at 0.40005 0 90)
			(size 0 0)
			(layers "B.Cu" "B.Mask" "B.Paste")
			(net "P12V_LED_ISET")
		)
		(pad "2" smd circle
			(at -0.40005 0 90)
			(size 0 0)
			(layers "B.Cu" "B.Mask" "B.Paste")
			(net "P12V_LED_ISET_R")
		)
	)
	(footprint ""
		(layer "B.Cu")
		(at 178.2064 -61.468)
		(property "Reference" "PC607"
			(at 0 0 0)
			(layer "B.SilkS")
			(hide yes)
			(effects
				(font
					(size 1.27 1.27)
				)
				(justify mirror)
			)
		)
		(property "Value" ""
			(at 0 0 0)
			(layer "B.Fab")
			(effects
				(font
					(size 1.27 1.27)
				)
				(justify mirror)
			)
		)
		(duplicate_pad_numbers_are_jumpers no)
		(fp_line
			(start -2.2098 -0.9398)
			(end -2.2098 0.9398)
			(stroke
				(width 0.1524)
				(type default)
			)
			(layer "B.SilkS")
		)
		(fp_line
			(start -2.2098 0.9398)
			(end 2.2098 0.9398)
			(stroke
				(width 0.1524)
				(type default)
			)
			(layer "B.SilkS")
		)
		(fp_line
			(start 2.2098 -0.9398)
			(end -2.2098 -0.9398)
			(stroke
				(width 0.1524)
				(type default)
			)
			(layer "B.SilkS")
		)
		(fp_line
			(start 2.2098 0.9398)
			(end 2.2098 -0.9398)
			(stroke
				(width 0.1524)
				(type default)
			)
			(layer "B.SilkS")
		)
		(fp_line
			(start -1.6764 -0.9398)
			(end 1.6764 -0.9398)
			(stroke
				(width 0.1)
				(type default)
			)
			(layer "B.Fab")
		)
		(fp_line
			(start -1.6764 0.9398)
			(end -1.6764 -0.9398)
			(stroke
				(width 0.1)
				(type default)
			)
			(layer "B.Fab")
		)
		(fp_line
			(start 1.6764 -0.9398)
			(end 1.6764 0.9398)
			(stroke
				(width 0.1)
				(type default)
			)
			(layer "B.Fab")
		)
		(fp_line
			(start 1.6764 0.9398)
			(end -1.6764 0.9398)
			(stroke
				(width 0.1)
				(type default)
			)
			(layer "B.Fab")
		)
		(pad "1" smd rect
			(at 1.4732 0)
			(size 1.1684 1.5748)
			(layers "B.Cu" "B.Mask" "B.Paste")
			(net "P52V_HS2_VCC")
		)
		(pad "2" smd rect
			(at -1.4732 0)
			(size 1.1684 1.5748)
			(layers "B.Cu" "B.Mask" "B.Paste")
			(net "GND1_FIELD_SIGNAL")
		)
	)
	(footprint ""
		(layer "B.Cu")
		(at 271.1704 -63.5)
		(property "Reference" "PR6935"
			(at 0 0 0)
			(layer "B.SilkS")
			(hide yes)
			(effects
				(font
					(size 1.27 1.27)
				)
				(justify mirror)
			)
		)
		(property "Value" ""
			(at 0 0 0)
			(layer "B.Fab")
			(effects
				(font
					(size 1.27 1.27)
				)
				(justify mirror)
			)
		)
		(duplicate_pad_numbers_are_jumpers no)
		(fp_line
			(start -0.7874 -0.4064)
			(end -0.7874 0.4064)
			(stroke
				(width 0.1524)
				(type default)
			)
			(layer "B.SilkS")
		)
		(fp_line
			(start -0.7874 0.4064)
			(end 0.7874 0.4064)
			(stroke
				(width 0.1524)
				(type default)
			)
			(layer "B.SilkS")
		)
		(fp_line
			(start 0.7874 -0.4064)
			(end -0.7874 -0.4064)
			(stroke
				(width 0.1524)
				(type default)
			)
			(layer "B.SilkS")
		)
		(fp_line
			(start 0.7874 0.4064)
			(end 0.7874 -0.4064)
			(stroke
				(width 0.1524)
				(type default)
			)
			(layer "B.SilkS")
		)
		(fp_line
			(start -0.67945 -0.3048)
			(end -0.67945 0.3048)
			(stroke
				(width 0.1)
				(type default)
			)
			(layer "B.Fab")
		)
		(fp_line
			(start -0.67945 0.3048)
			(end -0.120396 0.3048)
			(stroke
				(width 0.1)
				(type default)
			)
			(layer "B.Fab")
		)
		(fp_line
			(start -0.12065 -0.3048)
			(end -0.67945 -0.3048)
			(stroke
				(width 0.1)
				(type default)
			)
			(layer "B.Fab")
		)
		(fp_line
			(start -0.12065 -0.2794)
			(end -0.12065 -0.3048)
			(stroke
				(width 0.1)
				(type default)
			)
			(layer "B.Fab")
		)
		(fp_line
			(start -0.120396 0.2794)
			(end 0.12065 0.2794)
			(stroke
				(width 0.1)
				(type default)
			)
			(layer "B.Fab")
		)
		(fp_line
			(start -0.120396 0.3048)
			(end -0.120396 0.2794)
			(stroke
				(width 0.1)
				(type default)
			)
			(layer "B.Fab")
		)
		(fp_line
			(start 0.12065 -0.305054)
			(end 0.12065 -0.2794)
			(stroke
				(width 0.1)
				(type default)
			)
			(layer "B.Fab")
		)
		(fp_line
			(start 0.12065 -0.2794)
			(end -0.12065 -0.2794)
			(stroke
				(width 0.1)
				(type default)
			)
			(layer "B.Fab")
		)
		(fp_line
			(start 0.12065 0.2794)
			(end 0.12065 0.3048)
			(stroke
				(width 0.1)
				(type default)
			)
			(layer "B.Fab")
		)
		(fp_line
			(start 0.12065 0.3048)
			(end 0.67945 0.3048)
			(stroke
				(width 0.1)
				(type default)
			)
			(layer "B.Fab")
		)
		(fp_line
			(start 0.67945 -0.305054)
			(end 0.12065 -0.305054)
			(stroke
				(width 0.1)
				(type default)
			)
			(layer "B.Fab")
		)
		(fp_line
			(start 0.67945 0.3048)
			(end 0.67945 -0.305054)
			(stroke
				(width 0.1)
				(type default)
			)
			(layer "B.Fab")
		)
		(pad "1" smd circle
			(at 0.40005 0 180)
			(size 0 0)
			(layers "B.Cu" "B.Mask" "B.Paste")
			(net "PWRGD_P52V_HS1_PG")
		)
		(pad "2" smd circle
			(at -0.40005 0 180)
			(size 0 0)
			(layers "B.Cu" "B.Mask" "B.Paste")
			(net "P52V_HS1_PWRGIN")
		)
	)
	(footprint ""
		(layer "B.Cu")
		(at 278.4094 -63.881 180)
		(property "Reference" "PR35"
			(at 0 0 0)
			(layer "B.SilkS")
			(hide yes)
			(effects
				(font
					(size 1.27 1.27)
				)
				(justify mirror)
			)
		)
		(property "Value" ""
			(at 0 0 0)
			(layer "B.Fab")
			(effects
				(font
					(size 1.27 1.27)
				)
				(justify mirror)
			)
		)
		(duplicate_pad_numbers_are_jumpers no)
		(fp_line
			(start 0.7874 0.4064)
			(end 0.7874 -0.4064)
			(stroke
				(width 0.1524)
				(type default)
			)
			(layer "B.SilkS")
		)
		(fp_line
			(start 0.7874 -0.4064)
			(end -0.7874 -0.4064)
			(stroke
				(width 0.1524)
				(type default)
			)
			(layer "B.SilkS")
		)
		(fp_line
			(start -0.7874 0.4064)
			(end 0.7874 0.4064)
			(stroke
				(width 0.1524)
				(type default)
			)
			(layer "B.SilkS")
		)
		(fp_line
			(start -0.7874 -0.4064)
			(end -0.7874 0.4064)
			(stroke
				(width 0.1524)
				(type default)
			)
			(layer "B.SilkS")
		)
		(fp_line
			(start 0.67945 0.3048)
			(end 0.67945 -0.305054)
			(stroke
				(width 0.1)
				(type default)
			)
			(layer "B.Fab")
		)
		(fp_line
			(start 0.67945 -0.305054)
			(end 0.12065 -0.305054)
			(stroke
				(width 0.1)
				(type default)
			)
			(layer "B.Fab")
		)
		(fp_line
			(start 0.12065 0.3048)
			(end 0.67945 0.3048)
			(stroke
				(width 0.1)
				(type default)
			)
			(layer "B.Fab")
		)
		(fp_line
			(start 0.12065 0.2794)
			(end 0.12065 0.3048)
			(stroke
				(width 0.1)
				(type default)
			)
			(layer "B.Fab")
		)
		(fp_line
			(start 0.12065 -0.2794)
			(end -0.12065 -0.2794)
			(stroke
				(width 0.1)
				(type default)
			)
			(layer "B.Fab")
		)
		(fp_line
			(start 0.12065 -0.305054)
			(end 0.12065 -0.2794)
			(stroke
				(width 0.1)
				(type default)
			)
			(layer "B.Fab")
		)
		(fp_line
			(start -0.120396 0.3048)
			(end -0.120396 0.2794)
			(stroke
				(width 0.1)
				(type default)
			)
			(layer "B.Fab")
		)
		(fp_line
			(start -0.120396 0.2794)
			(end 0.12065 0.2794)
			(stroke
				(width 0.1)
				(type default)
			)
			(layer "B.Fab")
		)
		(fp_line
			(start -0.12065 -0.2794)
			(end -0.12065 -0.3048)
			(stroke
				(width 0.1)
				(type default)
			)
			(layer "B.Fab")
		)
		(fp_line
			(start -0.12065 -0.3048)
			(end -0.67945 -0.3048)
			(stroke
				(width 0.1)
				(type default)
			)
			(layer "B.Fab")
		)
		(fp_line
			(start -0.67945 0.3048)
			(end -0.120396 0.3048)
			(stroke
				(width 0.1)
				(type default)
			)
			(layer "B.Fab")
		)
		(fp_line
			(start -0.67945 -0.3048)
			(end -0.67945 0.3048)
			(stroke
				(width 0.1)
				(type default)
			)
			(layer "B.Fab")
		)
		(pad "1" smd circle
			(at 0.40005 0)
			(size 0 0)
			(layers "B.Cu" "B.Mask" "B.Paste")
			(net "P52V_HS1_MCB")
		)
		(pad "2" smd circle
			(at -0.40005 0)
			(size 0 0)
			(layers "B.Cu" "B.Mask" "B.Paste")
			(net "GND_FIELD_SIGNAL")
		)
	)
	(footprint ""
		(layer "B.Cu")
		(at 162.860736 -75.692 180)
		(property "Reference" "PC604"
			(at 0 0 0)
			(layer "B.SilkS")
			(hide yes)
			(effects
				(font
					(size 1.27 1.27)
				)
				(justify mirror)
			)
		)
		(property "Value" ""
			(at 0 0 0)
			(layer "B.Fab")
			(effects
				(font
					(size 1.27 1.27)
				)
				(justify mirror)
			)
		)
		(duplicate_pad_numbers_are_jumpers no)
		(fp_line
			(start 0.7874 0.4064)
			(end 0.7874 -0.4064)
			(stroke
				(width 0.1524)
				(type default)
			)
			(layer "B.SilkS")
		)
		(fp_line
			(start 0.7874 -0.4064)
			(end -0.7874 -0.4064)
			(stroke
				(width 0.1524)
				(type default)
			)
			(layer "B.SilkS")
		)
		(fp_line
			(start -0.7874 0.4064)
			(end 0.7874 0.4064)
			(stroke
				(width 0.1524)
				(type default)
			)
			(layer "B.SilkS")
		)
		(fp_line
			(start -0.7874 -0.4064)
			(end -0.7874 0.4064)
			(stroke
				(width 0.1524)
				(type default)
			)
			(layer "B.SilkS")
		)
		(fp_line
			(start 0.67945 0.3048)
			(end 0.67945 -0.305054)
			(stroke
				(width 0.1)
				(type default)
			)
			(layer "B.Fab")
		)
		(fp_line
			(start 0.67945 -0.305054)
			(end 0.12065 -0.305054)
			(stroke
				(width 0.1)
				(type default)
			)
			(layer "B.Fab")
		)
		(fp_line
			(start 0.12065 0.3048)
			(end 0.67945 0.3048)
			(stroke
				(width 0.1)
				(type default)
			)
			(layer "B.Fab")
		)
		(fp_line
			(start 0.12065 0.2794)
			(end 0.12065 0.3048)
			(stroke
				(width 0.1)
				(type default)
			)
			(layer "B.Fab")
		)
		(fp_line
			(start 0.12065 -0.2794)
			(end -0.12065 -0.2794)
			(stroke
				(width 0.1)
				(type default)
			)
			(layer "B.Fab")
		)
		(fp_line
			(start 0.12065 -0.305054)
			(end 0.12065 -0.2794)
			(stroke
				(width 0.1)
				(type default)
			)
			(layer "B.Fab")
		)
		(fp_line
			(start -0.120396 0.3048)
			(end -0.120396 0.2794)
			(stroke
				(width 0.1)
				(type default)
			)
			(layer "B.Fab")
		)
		(fp_line
			(start -0.120396 0.2794)
			(end 0.12065 0.2794)
			(stroke
				(width 0.1)
				(type default)
			)
			(layer "B.Fab")
		)
		(fp_line
			(start -0.12065 -0.2794)
			(end -0.12065 -0.3048)
			(stroke
				(width 0.1)
				(type default)
			)
			(layer "B.Fab")
		)
		(fp_line
			(start -0.12065 -0.3048)
			(end -0.67945 -0.3048)
			(stroke
				(width 0.1)
				(type default)
			)
			(layer "B.Fab")
		)
		(fp_line
			(start -0.67945 0.3048)
			(end -0.120396 0.3048)
			(stroke
				(width 0.1)
				(type default)
			)
			(layer "B.Fab")
		)
		(fp_line
			(start -0.67945 -0.3048)
			(end -0.67945 0.3048)
			(stroke
				(width 0.1)
				(type default)
			)
			(layer "B.Fab")
		)
		(pad "1" smd circle
			(at 0.40005 0)
			(size 0 0)
			(layers "B.Cu" "B.Mask" "B.Paste")
			(net "HS2_TMR1")
		)
		(pad "2" smd circle
			(at -0.40005 0)
			(size 0 0)
			(layers "B.Cu" "B.Mask" "B.Paste")
			(net "GND1_FIELD_SIGNAL")
		)
	)
	(footprint ""
		(layer "B.Cu")
		(at 169.1894 -77.343)
		(property "Reference" "R5890"
			(at 0 0 0)
			(layer "B.SilkS")
			(hide yes)
			(effects
				(font
					(size 1.27 1.27)
				)
				(justify mirror)
			)
		)
		(property "Value" ""
			(at 0 0 0)
			(layer "B.Fab")
			(effects
				(font
					(size 1.27 1.27)
				)
				(justify mirror)
			)
		)
		(duplicate_pad_numbers_are_jumpers no)
		(fp_line
			(start -0.7874 -0.4064)
			(end -0.7874 0.4064)
			(stroke
				(width 0.1524)
				(type default)
			)
			(layer "B.SilkS")
		)
		(fp_line
			(start -0.7874 0.4064)
			(end 0.7874 0.4064)
			(stroke
				(width 0.1524)
				(type default)
			)
			(layer "B.SilkS")
		)
		(fp_line
			(start 0.7874 -0.4064)
			(end -0.7874 -0.4064)
			(stroke
				(width 0.1524)
				(type default)
			)
			(layer "B.SilkS")
		)
		(fp_line
			(start 0.7874 0.4064)
			(end 0.7874 -0.4064)
			(stroke
				(width 0.1524)
				(type default)
			)
			(layer "B.SilkS")
		)
		(fp_line
			(start -0.67945 -0.3048)
			(end -0.67945 0.3048)
			(stroke
				(width 0.1)
				(type default)
			)
			(layer "B.Fab")
		)
		(fp_line
			(start -0.67945 0.3048)
			(end -0.120396 0.3048)
			(stroke
				(width 0.1)
				(type default)
			)
			(layer "B.Fab")
		)
		(fp_line
			(start -0.12065 -0.3048)
			(end -0.67945 -0.3048)
			(stroke
				(width 0.1)
				(type default)
			)
			(layer "B.Fab")
		)
		(fp_line
			(start -0.12065 -0.2794)
			(end -0.12065 -0.3048)
			(stroke
				(width 0.1)
				(type default)
			)
			(layer "B.Fab")
		)
		(fp_line
			(start -0.120396 0.2794)
			(end 0.12065 0.2794)
			(stroke
				(width 0.1)
				(type default)
			)
			(layer "B.Fab")
		)
		(fp_line
			(start -0.120396 0.3048)
			(end -0.120396 0.2794)
			(stroke
				(width 0.1)
				(type default)
			)
			(layer "B.Fab")
		)
		(fp_line
			(start 0.12065 -0.305054)
			(end 0.12065 -0.2794)
			(stroke
				(width 0.1)
				(type default)
			)
			(layer "B.Fab")
		)
		(fp_line
			(start 0.12065 -0.2794)
			(end -0.12065 -0.2794)
			(stroke
				(width 0.1)
				(type default)
			)
			(layer "B.Fab")
		)
		(fp_line
			(start 0.12065 0.2794)
			(end 0.12065 0.3048)
			(stroke
				(width 0.1)
				(type default)
			)
			(layer "B.Fab")
		)
		(fp_line
			(start 0.12065 0.3048)
			(end 0.67945 0.3048)
			(stroke
				(width 0.1)
				(type default)
			)
			(layer "B.Fab")
		)
		(fp_line
			(start 0.67945 -0.305054)
			(end 0.12065 -0.305054)
			(stroke
				(width 0.1)
				(type default)
			)
			(layer "B.Fab")
		)
		(fp_line
			(start 0.67945 0.3048)
			(end 0.67945 -0.305054)
			(stroke
				(width 0.1)
				(type default)
			)
			(layer "B.Fab")
		)
		(pad "1" smd circle
			(at 0.40005 0 180)
			(size 0 0)
			(layers "B.Cu" "B.Mask" "B.Paste")
			(net "P52V_HS2_GPO1")
		)
		(pad "2" smd circle
			(at -0.40005 0 180)
			(size 0 0)
			(layers "B.Cu" "B.Mask" "B.Paste")
			(net "P52V_HS2_FLT")
		)
	)
)
